(kicad_pcb
	(version 20260206)
	(generator "pcbnew")
	(generator_version "10.0")
	(general
		(thickness 1.6)
		(legacy_teardrops no)
	)
	(paper "A4")
	(title_block
		(title "pdpb — Lightning_PDPB_BRD.brd")
		(comment 1 "Lightning (Wiwynn / Facebook NVMe JBOF) / footprints 451-455 of 1140")
	)
	(layers
		(0 "F.Cu" signal "TOP")
		(4 "In1.Cu" signal "L2GND")
		(6 "In2.Cu" signal "L3")
		(8 "In3.Cu" signal "L4VCC")
		(10 "In4.Cu" signal "L5VCC")
		(12 "In5.Cu" signal "L6")
		(14 "In6.Cu" signal "L7GND")
		(2 "B.Cu" signal "BOTTOM")
		(9 "F.Adhes" user "F.Adhesive")
		(11 "B.Adhes" user "B.Adhesive")
		(13 "F.Paste" user "Package Geometry/Pastemask Top")
		(15 "B.Paste" user "Package Geometry/Pastemask Bottom")
		(5 "F.SilkS" user "Ref Des/Silkscreen Top")
		(7 "B.SilkS" user "Ref Des/Silkscreen Bottom")
		(1 "F.Mask" user "Board Geometry/Soldermask Top")
		(3 "B.Mask" user "Board Geometry/Soldermask Bottom")
		(17 "Dwgs.User" user "User.Drawings")
		(19 "Cmts.User" user "User.Comments")
		(21 "Eco1.User" user "User.Eco1")
		(23 "Eco2.User" user "User.Eco2")
		(25 "Edge.Cuts" user "Board Geometry/Outline")
		(27 "Margin" user)
		(31 "F.CrtYd" user "Package Geometry/Place Bound Top")
		(29 "B.CrtYd" user "Package Geometry/Place Bound Bottom")
		(35 "F.Fab" user "Ref Des/Assembly Top")
		(33 "B.Fab" user "Ref Des/Assembly Bottom")
	)
	(footprint ""
		(layer "F.Cu")
		(at 221.996 -194.437 180)
		(property "Reference" "PC1225"
			(at 0 0 180)
			(layer "F.SilkS")
			(hide yes)
			(effects
				(font
					(size 1.27 1.27)
				)
			)
		)
		(property "Value" "SC22U25V6KX-GP-U"
			(at -2.860802 -5.279644 180)
			(unlocked yes)
			(layer "F.Fab")
			(hide yes)
			(effects
				(font
					(size 1.016 1.016)
					(thickness 0.1524)
				)
			)
		)
		(property "Device Type" "C1206-TO0D3H75"
			(at -2.860802 -6.803644 180)
			(unlocked yes)
			(layer "F.Fab")
			(hide yes)
			(effects
				(font
					(size 1.016 1.016)
					(thickness 0.1524)
				)
			)
		)
		(duplicate_pad_numbers_are_jumpers no)
		(fp_line
			(start 1.3081 2.3749)
			(end -1.3081 2.3749)
			(stroke
				(width 0.1524)
				(type default)
			)
			(layer "F.SilkS")
		)
		(fp_line
			(start 1.3081 -2.3749)
			(end 1.3081 2.3749)
			(stroke
				(width 0.1524)
				(type default)
			)
			(layer "F.SilkS")
		)
		(fp_line
			(start -1.3081 2.3749)
			(end -1.3081 -2.3749)
			(stroke
				(width 0.1524)
				(type default)
			)
			(layer "F.SilkS")
		)
		(fp_line
			(start -1.3081 -2.3749)
			(end 1.3081 -2.3749)
			(stroke
				(width 0.1524)
				(type default)
			)
			(layer "F.SilkS")
		)
		(fp_rect
			(start -0.8001 1.6002)
			(end 0.8001 -1.6002)
			(stroke
				(width 0)
				(type default)
			)
			(fill no)
			(layer "F.CrtYd")
		)
		(fp_poly
			(pts
				(xy -1.5621 2.4511) (xy -1.5621 1.6002) (xy 0.8001 1.6002) (xy 0.8001 -1.6002) (xy -0.8001 -1.6002)
				(xy -0.8001 1.5875) (xy -1.5621 1.5875) (xy -1.5621 -2.4511) (xy 1.5621 -2.4511) (xy 1.5621 2.4511)
			)
			(stroke
				(width 0)
				(type default)
			)
			(fill no)
			(layer "F.CrtYd")
		)
		(fp_rect
			(start -1.5621 2.4511)
			(end 1.5621 -2.4511)
			(stroke
				(width 0)
				(type default)
			)
			(fill no)
			(layer "F.Fab")
		)
		(pad "1" smd rect
			(at 0 -1.392936 180)
			(size 2.1082 1.4478)
			(layers "F.Cu" "F.Mask" "F.Paste")
			(net "P12V_SSD3")
		)
		(pad "2" smd rect
			(at 0 1.392936 180)
			(size 2.1082 1.4478)
			(layers "F.Cu" "F.Mask" "F.Paste")
			(net "GND")
		)
	)
	(footprint ""
		(layer "F.Cu")
		(at 38.851586 -342.341708 90)
		(property "Reference" "R9918"
			(at 0 0 90)
			(layer "F.SilkS")
			(hide yes)
			(effects
				(font
					(size 1.27 1.27)
				)
			)
		)
		(property "Value" "47KR2J-2-GP"
			(at 0.064008 -3.993896 90)
			(unlocked yes)
			(layer "F.Fab")
			(hide yes)
			(effects
				(font
					(size 1.016 1.016)
					(thickness 0.1524)
				)
			)
		)
		(property "Device Type" "R402H16"
			(at 0.064008 -5.517896 90)
			(unlocked yes)
			(layer "F.Fab")
			(hide yes)
			(effects
				(font
					(size 1.016 1.016)
					(thickness 0.1524)
				)
			)
		)
		(duplicate_pad_numbers_are_jumpers no)
		(fp_line
			(start 0.508 -0.9398)
			(end -0.508 -0.9398)
			(stroke
				(width 0.1524)
				(type default)
			)
			(layer "F.SilkS")
		)
		(fp_line
			(start -0.508 -0.9398)
			(end -0.508 0.9398)
			(stroke
				(width 0.1524)
				(type default)
			)
			(layer "F.SilkS")
		)
		(fp_rect
			(start -0.508 0.9398)
			(end 0.508 -0.9398)
			(stroke
				(width 0)
				(type default)
			)
			(fill no)
			(layer "F.CrtYd")
		)
		(fp_rect
			(start -0.508 0.9398)
			(end 0.508 -0.9398)
			(stroke
				(width 0)
				(type default)
			)
			(fill no)
			(layer "F.Fab")
		)
		(pad "1" smd custom
			(at 0 -0.4445 90)
			(size 0.1397 0.1397)
			(layers "F.Cu" "F.Mask" "F.Paste")
			(net "P3V3")
			(options
				(clearance outline)
				(anchor circle)
			)
			(primitives
				(gr_poly
					(pts
						(arc
							(start -0.1778 -0.2794)
							(mid -0.249642 -0.249642)
							(end -0.2794 -0.1778)
						)
						(arc
							(start -0.2794 0.1778)
							(mid -0.249642 0.249642)
							(end -0.1778 0.2794)
						)
						(arc
							(start 0.1778 0.2794)
							(mid 0.249642 0.249642)
							(end 0.2794 0.1778)
						)
						(arc
							(start 0.2794 -0.1778)
							(mid 0.249642 -0.249642)
							(end 0.1778 -0.2794)
						)
					)
					(width 0)
					(fill yes)
				)
			)
		)
		(pad "2" smd custom
			(at 0 0.4445 90)
			(size 0.1397 0.1397)
			(layers "F.Cu" "F.Mask" "F.Paste")
			(net "ATTN_LED_DR6_N")
			(options
				(clearance outline)
				(anchor circle)
			)
			(primitives
				(gr_poly
					(pts
						(arc
							(start -0.1778 -0.2794)
							(mid -0.249642 -0.249642)
							(end -0.2794 -0.1778)
						)
						(arc
							(start -0.2794 0.1778)
							(mid -0.249642 0.249642)
							(end -0.1778 0.2794)
						)
						(arc
							(start 0.1778 0.2794)
							(mid 0.249642 0.249642)
							(end 0.2794 0.1778)
						)
						(arc
							(start 0.2794 -0.1778)
							(mid 0.249642 -0.249642)
							(end 0.1778 -0.2794)
						)
					)
					(width 0)
					(fill yes)
				)
			)
		)
	)
	(footprint ""
		(layer "F.Cu")
		(at 219.329 -346.579952 90)
		(property "Reference" "SR1123"
			(at 0 0 90)
			(layer "F.SilkS")
			(hide yes)
			(effects
				(font
					(size 1.27 1.27)
				)
			)
		)
		(property "Value" "4K7R2F-GP"
			(at 0.064008 -3.993896 90)
			(unlocked yes)
			(layer "F.Fab")
			(hide yes)
			(effects
				(font
					(size 1.016 1.016)
					(thickness 0.1524)
				)
			)
		)
		(property "Device Type" "R402H16"
			(at 0.064008 -5.517896 90)
			(unlocked yes)
			(layer "F.Fab")
			(hide yes)
			(effects
				(font
					(size 1.016 1.016)
					(thickness 0.1524)
				)
			)
		)
		(duplicate_pad_numbers_are_jumpers no)
		(fp_line
			(start 0.508 -0.9398)
			(end -0.508 -0.9398)
			(stroke
				(width 0.1524)
				(type default)
			)
			(layer "F.SilkS")
		)
		(fp_line
			(start -0.508 -0.9398)
			(end -0.508 0.9398)
			(stroke
				(width 0.1524)
				(type default)
			)
			(layer "F.SilkS")
		)
		(fp_rect
			(start -0.508 0.9398)
			(end 0.508 -0.9398)
			(stroke
				(width 0)
				(type default)
			)
			(fill no)
			(layer "F.CrtYd")
		)
		(fp_rect
			(start -0.508 0.9398)
			(end 0.508 -0.9398)
			(stroke
				(width 0)
				(type default)
			)
			(fill no)
			(layer "F.Fab")
		)
		(pad "1" smd custom
			(at 0 -0.4445 90)
			(size 0.1397 0.1397)
			(layers "F.Cu" "F.Mask" "F.Paste")
			(net "P3V3")
			(options
				(clearance outline)
				(anchor circle)
			)
			(primitives
				(gr_poly
					(pts
						(arc
							(start -0.1778 -0.2794)
							(mid -0.249642 -0.249642)
							(end -0.2794 -0.1778)
						)
						(arc
							(start -0.2794 0.1778)
							(mid -0.249642 0.249642)
							(end -0.1778 0.2794)
						)
						(arc
							(start 0.1778 0.2794)
							(mid 0.249642 0.249642)
							(end 0.2794 0.1778)
						)
						(arc
							(start 0.2794 -0.1778)
							(mid 0.249642 -0.249642)
							(end 0.1778 -0.2794)
						)
					)
					(width 0)
					(fill yes)
				)
			)
		)
		(pad "2" smd custom
			(at 0 0.4445 90)
			(size 0.1397 0.1397)
			(layers "F.Cu" "F.Mask" "F.Paste")
			(net "SSD1_CLK0_OE_MOS_N")
			(options
				(clearance outline)
				(anchor circle)
			)
			(primitives
				(gr_poly
					(pts
						(arc
							(start -0.1778 -0.2794)
							(mid -0.249642 -0.249642)
							(end -0.2794 -0.1778)
						)
						(arc
							(start -0.2794 0.1778)
							(mid -0.249642 0.249642)
							(end -0.1778 0.2794)
						)
						(arc
							(start 0.1778 0.2794)
							(mid 0.249642 0.249642)
							(end 0.2794 0.1778)
						)
						(arc
							(start 0.2794 -0.1778)
							(mid 0.249642 -0.249642)
							(end 0.1778 -0.2794)
						)
					)
					(width 0)
					(fill yes)
				)
			)
		)
	)
	(footprint ""
		(layer "F.Cu")
		(at 31.051754 -215.200484)
		(property "Reference" "SR1116"
			(at 0 0 0)
			(layer "F.SilkS")
			(hide yes)
			(effects
				(font
					(size 1.27 1.27)
				)
			)
		)
		(property "Value" "4K7R2F-GP"
			(at 0.064008 -3.993896 0)
			(unlocked yes)
			(layer "F.Fab")
			(hide yes)
			(effects
				(font
					(size 1.016 1.016)
					(thickness 0.1524)
				)
			)
		)
		(property "Device Type" "R402H16"
			(at 0.064008 -5.517896 0)
			(unlocked yes)
			(layer "F.Fab")
			(hide yes)
			(effects
				(font
					(size 1.016 1.016)
					(thickness 0.1524)
				)
			)
		)
		(duplicate_pad_numbers_are_jumpers no)
		(fp_line
			(start -0.508 -0.9398)
			(end -0.508 0.9398)
			(stroke
				(width 0.1524)
				(type default)
			)
			(layer "F.SilkS")
		)
		(fp_line
			(start 0.508 -0.9398)
			(end -0.508 -0.9398)
			(stroke
				(width 0.1524)
				(type default)
			)
			(layer "F.SilkS")
		)
		(fp_rect
			(start -0.508 0.9398)
			(end 0.508 -0.9398)
			(stroke
				(width 0)
				(type default)
			)
			(fill no)
			(layer "F.CrtYd")
		)
		(fp_rect
			(start -0.508 0.9398)
			(end 0.508 -0.9398)
			(stroke
				(width 0)
				(type default)
			)
			(fill no)
			(layer "F.Fab")
		)
		(pad "1" smd custom
			(at 0 -0.4445)
			(size 0.1397 0.1397)
			(layers "F.Cu" "F.Mask" "F.Paste")
			(net "DUALPORTEN#12")
			(options
				(clearance outline)
				(anchor circle)
			)
			(primitives
				(gr_poly
					(pts
						(arc
							(start -0.1778 -0.2794)
							(mid -0.249642 -0.249642)
							(end -0.2794 -0.1778)
						)
						(arc
							(start -0.2794 0.1778)
							(mid -0.249642 0.249642)
							(end -0.1778 0.2794)
						)
						(arc
							(start 0.1778 0.2794)
							(mid 0.249642 0.249642)
							(end 0.2794 0.1778)
						)
						(arc
							(start 0.2794 -0.1778)
							(mid 0.249642 -0.249642)
							(end 0.1778 -0.2794)
						)
					)
					(width 0)
					(fill yes)
				)
			)
		)
		(pad "2" smd custom
			(at 0 0.4445)
			(size 0.1397 0.1397)
			(layers "F.Cu" "F.Mask" "F.Paste")
			(net "GND")
			(options
				(clearance outline)
				(anchor circle)
			)
			(primitives
				(gr_poly
					(pts
						(arc
							(start -0.1778 -0.2794)
							(mid -0.249642 -0.249642)
							(end -0.2794 -0.1778)
						)
						(arc
							(start -0.2794 0.1778)
							(mid -0.249642 0.249642)
							(end -0.1778 0.2794)
						)
						(arc
							(start 0.1778 0.2794)
							(mid 0.249642 0.249642)
							(end 0.2794 0.1778)
						)
						(arc
							(start 0.2794 -0.1778)
							(mid 0.249642 -0.249642)
							(end 0.1778 -0.2794)
						)
					)
					(width 0)
					(fill yes)
				)
			)
		)
	)
	(footprint ""
		(layer "F.Cu")
		(at 102.616 -208.28 90)
		(property "Reference" "R9081"
			(at 0 0 90)
			(layer "F.SilkS")
			(hide yes)
			(effects
				(font
					(size 1.27 1.27)
				)
			)
		)
		(property "Value" "27R2F-GP"
			(at 0.064008 -3.993896 90)
			(unlocked yes)
			(layer "F.Fab")
			(hide yes)
			(effects
				(font
					(size 1.016 1.016)
					(thickness 0.1524)
				)
			)
		)
		(property "Device Type" "R402H16"
			(at 0.064008 -5.517896 90)
			(unlocked yes)
			(layer "F.Fab")
			(hide yes)
			(effects
				(font
					(size 1.016 1.016)
					(thickness 0.1524)
				)
			)
		)
		(duplicate_pad_numbers_are_jumpers no)
		(fp_line
			(start 0.508 -0.9398)
			(end -0.508 -0.9398)
			(stroke
				(width 0.1524)
				(type default)
			)
			(layer "F.SilkS")
		)
		(fp_line
			(start -0.508 -0.9398)
			(end -0.508 0.9398)
			(stroke
				(width 0.1524)
				(type default)
			)
			(layer "F.SilkS")
		)
		(fp_rect
			(start -0.508 0.9398)
			(end 0.508 -0.9398)
			(stroke
				(width 0)
				(type default)
			)
			(fill no)
			(layer "F.CrtYd")
		)
		(fp_rect
			(start -0.508 0.9398)
			(end 0.508 -0.9398)
			(stroke
				(width 0)
				(type default)
			)
			(fill no)
			(layer "F.Fab")
		)
		(pad "1" smd custom
			(at 0 -0.4445 90)
			(size 0.1397 0.1397)
			(layers "F.Cu" "F.Mask" "F.Paste")
			(net "PE_CLK_100M_DR3_1_R_P")
			(options
				(clearance outline)
				(anchor circle)
			)
			(primitives
				(gr_poly
					(pts
						(arc
							(start -0.1778 -0.2794)
							(mid -0.249642 -0.249642)
							(end -0.2794 -0.1778)
						)
						(arc
							(start -0.2794 0.1778)
							(mid -0.249642 0.249642)
							(end -0.1778 0.2794)
						)
						(arc
							(start 0.1778 0.2794)
							(mid 0.249642 0.249642)
							(end 0.2794 0.1778)
						)
						(arc
							(start 0.2794 -0.1778)
							(mid 0.249642 -0.249642)
							(end 0.1778 -0.2794)
						)
					)
					(width 0)
					(fill yes)
				)
			)
		)
		(pad "2" smd custom
			(at 0 0.4445 90)
			(size 0.1397 0.1397)
			(layers "F.Cu" "F.Mask" "F.Paste")
			(net "PE_CLK100M_DR3_1_P")
			(options
				(clearance outline)
				(anchor circle)
			)
			(primitives
				(gr_poly
					(pts
						(arc
							(start -0.1778 -0.2794)
							(mid -0.249642 -0.249642)
							(end -0.2794 -0.1778)
						)
						(arc
							(start -0.2794 0.1778)
							(mid -0.249642 0.249642)
							(end -0.1778 0.2794)
						)
						(arc
							(start 0.1778 0.2794)
							(mid 0.249642 0.249642)
							(end 0.2794 0.1778)
						)
						(arc
							(start 0.2794 -0.1778)
							(mid 0.249642 -0.249642)
							(end 0.1778 -0.2794)
						)
					)
					(width 0)
					(fill yes)
				)
			)
		)
	)
)
